# T6G (Grand Teton) — schematic netlist excerpt (pin names and nets, part order shuffled) for the footprints in the layout excerpt that follows; sources: Cadence DE-HDL packaged netlist, KiCad conversion of 04192023_DAF0TMB3IC0_F0TG_MB_C_brd_V02_OCP.brd

C6592  Q_CAP_DIFFBUS  DIFF BUS_0.22UF 6.3V 20% X6S  pkg C0201  page 297 : \1\ = P5E_CPU0_P2_TX_BUF_C_DN<13> ; \2\ = P5E_CPU0_P2_TX_BUF_DN<13>
C6571  Q_CAP_DIFFBUS  DIFF BUS_0.22UF 6.3V 20% X6S  pkg C0201  page 297 : \1\ = P5E_CPU0_P2_TX_BUF_C_DP<3> ; \2\ = P5E_CPU0_P2_TX_BUF_DP<3>
R1107  Q_RES  4.7K 5% EMPTY  pkg 0201LF  page 309 : A = P1V8_CPU0_RT_1D ; B = RST_RT_CPU0_P3_RESET_R_N
R62  Q_RES  1K 1% CHIP  pkg 0402LF  page 238 : A = CPU_FRU_ADDR1 ; B = GND

(kicad_pcb
	(version 20260206)
	(generator "pcbnew")
	(generator_version "10.0")
	(general
		(thickness 1.6)
		(legacy_teardrops no)
	)
	(paper "A4")
	(title_block
		(title "04192023_DAF0TMB3IC0_F0TG_MB_C_brd_V02_OCP.brd")
		(comment 1 "Grand Teton / footprints 4691-4694 of 8354")
	)
	(layers
		(0 "F.Cu" signal "TOP")
		(4 "In1.Cu" signal "GND")
		(6 "In2.Cu" signal "IN1")
		(8 "In3.Cu" signal "GND1")
		(10 "In4.Cu" signal "IN2")
		(12 "In5.Cu" signal "GND2")
		(14 "In6.Cu" signal "IN3")
		(16 "In7.Cu" signal "GND3")
		(18 "In8.Cu" signal "VCC")
		(20 "In9.Cu" signal "VCC1")
		(22 "In10.Cu" signal "GND4")
		(24 "In11.Cu" signal "IN4")
		(26 "In12.Cu" signal "GND5")
		(28 "In13.Cu" signal "IN5")
		(30 "In14.Cu" signal "GND6")
		(32 "In15.Cu" signal "IN6")
		(34 "In16.Cu" signal "GND7")
		(2 "B.Cu" signal "BOTTOM")
		(9 "F.Adhes" user "F.Adhesive")
		(11 "B.Adhes" user "B.Adhesive")
		(13 "F.Paste" user "Package Geometry/Pastemask Top")
		(15 "B.Paste" user "Package Geometry/Pastemask Bottom")
		(5 "F.SilkS" user "Ref Des/Silkscreen Top")
		(7 "B.SilkS" user "Ref Des/Silkscreen Bottom")
		(1 "F.Mask" user "Board Geometry/Soldermask Top")
		(3 "B.Mask" user "Board Geometry/Soldermask Bottom")
		(17 "Dwgs.User" user "User.Drawings")
		(19 "Cmts.User" user "User.Comments")
		(21 "Eco1.User" user "User.Eco1")
		(23 "Eco2.User" user "User.Eco2")
		(25 "Edge.Cuts" user "Board Geometry/Outline")
		(27 "Margin" user)
		(31 "F.CrtYd" user "Package Geometry/Place Bound Top")
		(29 "B.CrtYd" user "Package Geometry/Place Bound Bottom")
		(35 "F.Fab" user "Ref Des/Assembly Top")
		(33 "B.Fab" user "Ref Des/Assembly Bottom")
	)
	(footprint ""
		(layer "F.Cu")
		(at 410.690822 -416.899344 -90)
		(property "Reference" "C6592"
			(at 0 0 270)
			(layer "F.SilkS")
			(hide yes)
			(effects
				(font
					(size 1.27 1.27)
				)
			)
		)
		(property "Value" ""
			(at 0 0 270)
			(layer "F.Fab")
			(effects
				(font
					(size 1.27 1.27)
				)
			)
		)
		(duplicate_pad_numbers_are_jumpers no)
		(fp_line
			(start -0.299974 0.150114)
			(end -0.299974 -0.150114)
			(stroke
				(width 0.1)
				(type default)
			)
			(layer "F.Fab")
		)
		(fp_line
			(start 0.299974 0.150114)
			(end -0.299974 0.150114)
			(stroke
				(width 0.1)
				(type default)
			)
			(layer "F.Fab")
		)
		(fp_line
			(start -0.299974 -0.150114)
			(end 0.299974 -0.150114)
			(stroke
				(width 0.1)
				(type default)
			)
			(layer "F.Fab")
		)
		(fp_line
			(start 0.299974 -0.150114)
			(end 0.299974 0.150114)
			(stroke
				(width 0.1)
				(type default)
			)
			(layer "F.Fab")
		)
		(pad "1" smd rect
			(at -0.2667 0 270)
			(size 0.3048 0.381)
			(layers "F.Cu" "F.Mask" "F.Paste")
			(net "P5E_CPU0_P2_TX_BUF_C_DN<13>")
		)
		(pad "2" smd rect
			(at 0.2667 0 270)
			(size 0.3048 0.381)
			(layers "F.Cu" "F.Mask" "F.Paste")
			(net "P5E_CPU0_P2_TX_BUF_DN<13>")
		)
	)
	(footprint ""
		(layer "F.Cu")
		(at 380.972822 -416.899344 -90)
		(property "Reference" "C6571"
			(at 0 0 270)
			(layer "F.SilkS")
			(hide yes)
			(effects
				(font
					(size 1.27 1.27)
				)
			)
		)
		(property "Value" ""
			(at 0 0 270)
			(layer "F.Fab")
			(effects
				(font
					(size 1.27 1.27)
				)
			)
		)
		(duplicate_pad_numbers_are_jumpers no)
		(fp_line
			(start -0.299974 0.150114)
			(end -0.299974 -0.150114)
			(stroke
				(width 0.1)
				(type default)
			)
			(layer "F.Fab")
		)
		(fp_line
			(start 0.299974 0.150114)
			(end -0.299974 0.150114)
			(stroke
				(width 0.1)
				(type default)
			)
			(layer "F.Fab")
		)
		(fp_line
			(start -0.299974 -0.150114)
			(end 0.299974 -0.150114)
			(stroke
				(width 0.1)
				(type default)
			)
			(layer "F.Fab")
		)
		(fp_line
			(start 0.299974 -0.150114)
			(end 0.299974 0.150114)
			(stroke
				(width 0.1)
				(type default)
			)
			(layer "F.Fab")
		)
		(pad "1" smd rect
			(at -0.2667 0 270)
			(size 0.3048 0.381)
			(layers "F.Cu" "F.Mask" "F.Paste")
			(net "P5E_CPU0_P2_TX_BUF_C_DP<3>")
		)
		(pad "2" smd rect
			(at 0.2667 0 270)
			(size 0.3048 0.381)
			(layers "F.Cu" "F.Mask" "F.Paste")
			(net "P5E_CPU0_P2_TX_BUF_DP<3>")
		)
	)
	(footprint ""
		(layer "F.Cu")
		(at 302.241458 -111.811308 180)
		(property "Reference" "R62"
			(at 0 0 180)
			(layer "F.SilkS")
			(hide yes)
			(effects
				(font
					(size 1.27 1.27)
				)
			)
		)
		(property "Value" ""
			(at 0 0 180)
			(layer "F.Fab")
			(effects
				(font
					(size 1.27 1.27)
				)
			)
		)
		(duplicate_pad_numbers_are_jumpers no)
		(fp_line
			(start 0.7874 0.4064)
			(end -0.7874 0.4064)
			(stroke
				(width 0.1524)
				(type default)
			)
			(layer "F.SilkS")
		)
		(fp_line
			(start 0.7874 -0.4064)
			(end 0.7874 0.4064)
			(stroke
				(width 0.1524)
				(type default)
			)
			(layer "F.SilkS")
		)
		(fp_line
			(start -0.7874 0.4064)
			(end -0.7874 -0.4064)
			(stroke
				(width 0.1524)
				(type default)
			)
			(layer "F.SilkS")
		)
		(fp_line
			(start -0.7874 -0.4064)
			(end 0.7874 -0.4064)
			(stroke
				(width 0.1524)
				(type default)
			)
			(layer "F.SilkS")
		)
		(fp_line
			(start 0.67945 0.3048)
			(end 0.120396 0.3048)
			(stroke
				(width 0.1)
				(type default)
			)
			(layer "F.Fab")
		)
		(fp_line
			(start 0.67945 -0.3048)
			(end 0.67945 0.3048)
			(stroke
				(width 0.1)
				(type default)
			)
			(layer "F.Fab")
		)
		(fp_line
			(start 0.12065 -0.2794)
			(end 0.12065 -0.3048)
			(stroke
				(width 0.1)
				(type default)
			)
			(layer "F.Fab")
		)
		(fp_line
			(start 0.12065 -0.3048)
			(end 0.67945 -0.3048)
			(stroke
				(width 0.1)
				(type default)
			)
			(layer "F.Fab")
		)
		(fp_line
			(start 0.120396 0.3048)
			(end 0.120396 0.2794)
			(stroke
				(width 0.1)
				(type default)
			)
			(layer "F.Fab")
		)
		(fp_line
			(start 0.120396 0.2794)
			(end -0.12065 0.2794)
			(stroke
				(width 0.1)
				(type default)
			)
			(layer "F.Fab")
		)
		(fp_line
			(start -0.12065 0.3048)
			(end -0.67945 0.3048)
			(stroke
				(width 0.1)
				(type default)
			)
			(layer "F.Fab")
		)
		(fp_line
			(start -0.12065 0.2794)
			(end -0.12065 0.3048)
			(stroke
				(width 0.1)
				(type default)
			)
			(layer "F.Fab")
		)
		(fp_line
			(start -0.12065 -0.2794)
			(end 0.12065 -0.2794)
			(stroke
				(width 0.1)
				(type default)
			)
			(layer "F.Fab")
		)
		(fp_line
			(start -0.12065 -0.305054)
			(end -0.12065 -0.2794)
			(stroke
				(width 0.1)
				(type default)
			)
			(layer "F.Fab")
		)
		(fp_line
			(start -0.67945 0.3048)
			(end -0.67945 -0.305054)
			(stroke
				(width 0.1)
				(type default)
			)
			(layer "F.Fab")
		)
		(fp_line
			(start -0.67945 -0.305054)
			(end -0.12065 -0.305054)
			(stroke
				(width 0.1)
				(type default)
			)
			(layer "F.Fab")
		)
		(pad "1" smd circle
			(at -0.40005 0 180)
			(size 0 0)
			(layers "F.Cu" "F.Mask" "F.Paste")
			(net "CPU_FRU_ADDR1")
		)
		(pad "2" smd circle
			(at 0.40005 0 180)
			(size 0 0)
			(layers "F.Cu" "F.Mask" "F.Paste")
			(net "GND")
		)
	)
	(footprint ""
		(layer "F.Cu")
		(at 367.787936 -403.818852 -90)
		(property "Reference" "R1107"
			(at 0 0 270)
			(layer "F.SilkS")
			(hide yes)
			(effects
				(font
					(size 1.27 1.27)
				)
			)
		)
		(property "Value" ""
			(at 0 0 270)
			(layer "F.Fab")
			(effects
				(font
					(size 1.27 1.27)
				)
			)
		)
		(duplicate_pad_numbers_are_jumpers no)
		(fp_line
			(start -0.32512 0.175006)
			(end -0.32512 -0.175006)
			(stroke
				(width 0.1)
				(type default)
			)
			(layer "F.Fab")
		)
		(fp_line
			(start 0.32512 0.175006)
			(end -0.32512 0.175006)
			(stroke
				(width 0.1)
				(type default)
			)
			(layer "F.Fab")
		)
		(fp_line
			(start -0.32512 -0.175006)
			(end 0.32512 -0.175006)
			(stroke
				(width 0.1)
				(type default)
			)
			(layer "F.Fab")
		)
		(fp_line
			(start 0.32512 -0.175006)
			(end 0.32512 0.175006)
			(stroke
				(width 0.1)
				(type default)
			)
			(layer "F.Fab")
		)
		(pad "1" smd rect
			(at -0.2667 0 270)
			(size 0.3048 0.381)
			(layers "F.Cu" "F.Mask" "F.Paste")
			(net "P1V8_CPU0_RT_1D")
		)
		(pad "2" smd rect
			(at 0.2667 0 90)
			(size 0.3048 0.381)
			(layers "F.Cu" "F.Mask" "F.Paste")
			(net "RST_RT_CPU0_P3_RESET_R_N")
		)
	)
)
